(kicad_pcb
	(version 20221018)
	(generator pcbnew)
	(general
    (thickness 1.562)
  )
	(paper "A4")
	(title_block
    (title "Thunderbolt PCIe Adaper")
    (date "2024-07-09")
    (rev "1.0.3")
    (comment 1 "www.antmicro.com")
    (comment 2 "Antmicro Ltd.")
		(comment 9 "footprints 263-271 of 271")
	)
	(layers
    (0 "F.Cu" signal)
    (1 "In1.Cu" signal)
    (2 "In2.Cu" signal)
    (3 "In3.Cu" signal)
    (4 "In4.Cu" signal)
    (31 "B.Cu" signal)
    (32 "B.Adhes" user "B.Adhesive")
    (33 "F.Adhes" user "F.Adhesive")
    (34 "B.Paste" user)
    (35 "F.Paste" user)
    (36 "B.SilkS" user "B.Silkscreen")
    (37 "F.SilkS" user "F.Silkscreen")
    (38 "B.Mask" user)
    (39 "F.Mask" user)
    (40 "Dwgs.User" user "User.Drawings")
    (41 "Cmts.User" user "User.Comments")
    (42 "Eco1.User" user "User.Eco1")
    (43 "Eco2.User" user "User.Eco2")
    (44 "Edge.Cuts" user)
    (45 "Margin" user)
    (46 "B.CrtYd" user "B.Courtyard")
    (47 "F.CrtYd" user "F.Courtyard")
    (48 "B.Fab" user)
    (49 "F.Fab" user)
  )
	(footprint "antmicro-footprints:R_0402_1005Metric" (layer "B.Cu")
    (at 155.41 62.97)
    (descr "Resistor SMD 0402")
    (tags "resistor SMD 0402")
    (property "Author" "Antmicro")
    (property "License" "Apache-2.0")
    (property "MPN" "ERA-2ARB153X")
    (property "Manufacturer" "Panasonic")
    (property "Sheetfile" "power.kicad_sch")
    (property "Sheetname" "Power")
    (property "Tolerance" "0.1%")
    (property "Val" "15k")
    (property "ki_description" "SMD Chip Resistor, 15 kohm, ± 0.1%, 62.5 mW, 0402 [1005 Metric], Metal Film (Thin Film)")
    (property "ki_keywords" "0402, SMT, RESISTOR, PASSIVE")
    (attr smd)
    (fp_text reference "R35" (at 2.897664 0.40289 180) (layer "B.SilkS")
        (effects (font (size 0.7 0.7) (thickness 0.15)) (justify left bottom mirror))
    )
    (fp_text value "R_15k_0.1%_0402" (at -1.011843 -1.772047 180) (layer "B.Fab")
        (effects (font (size 0.7 0.7) (thickness 0.15)) (justify left bottom mirror))
    )
    (fp_text user "${REFERENCE}" (at -0.95 -3.168 180) (layer "B.Fab") hide
        (effects (font (size 0.7 0.7) (thickness 0.15)) (justify left bottom mirror))
    )
    (fp_text user "Author: Antmicro" (at -0.95 -4.169 180) (layer "B.Fab") hide
        (effects (font (size 0.7 0.7) (thickness 0.15)) (justify left bottom mirror))
    )
    (fp_text user "License: Apache-2.0" (at -0.95 -5.169 180) (layer "B.Fab") hide
        (effects (font (size 0.7 0.7) (thickness 0.15)) (justify left bottom mirror))
    )
    (fp_rect (start -0.925 0.47) (end 0.925 -0.47)
      (stroke (width 0.05) (type default)) (fill none) (layer "B.CrtYd"))
    (fp_rect (start -0.5 0.25) (end 0.5 -0.25)
      (stroke (width 0.15) (type solid)) (fill none) (layer "B.Fab"))
    (pad "1" smd roundrect (at -0.48 0) (size 0.59 0.64) (layers "B.Cu" "B.Paste" "B.Mask") (roundrect_rratio 0.25)
      (net 168 "Net-(U3-R_OSC)") (pintype "passive"))
    (pad "2" smd roundrect (at 0.48 0) (size 0.59 0.64) (layers "B.Cu" "B.Paste" "B.Mask") (roundrect_rratio 0.25)
      (net 1 "GND") (pintype "passive"))
  )
	(footprint "antmicro-footprints:C_0402_1005Metric" (layer "B.Cu")
    (at 134.8 78.875)
    (descr "Capacitor SMD 0402")
    (tags "capacitor SMD 0402")
    (property "Author" "Antmicro")
    (property "Dielectric" "")
    (property "License" "Apache-2.0")
    (property "MPN" "C1005X6S1A105K050BC")
    (property "Manufacturer" "TDK")
    (property "Sheetfile" "tb-power.kicad_sch")
    (property "Sheetname" "Thunderbolt Controller - Power")
    (property "Val" "1u")
    (property "Voltage" "")
    (property "ki_description" "SMD Multilayer Ceramic Capacitor, 1 µF, 10 V, 0402 [1005 Metric], ± 10%, X6S, C")
    (property "ki_keywords" "0402, SMT, CAPACITOR, PASSIVE, CERAMIC, MLCC")
    (attr smd)
    (fp_text reference "C74" (at 17.6 7.612 180) (layer "B.SilkS")
        (effects (font (size 0.7 0.7) (thickness 0.15)) (justify left bottom mirror))
    )
    (fp_text value "C_1u_0402" (at -1.022927 -2.155213 180) (layer "B.Fab")
        (effects (font (size 0.7 0.7) (thickness 0.15)) (justify left bottom mirror))
    )
    (fp_text user "Author: Antmicro" (at -0.939 -3.399 180) (layer "B.Fab") hide
        (effects (font (size 0.7 0.7) (thickness 0.15)) (justify left bottom mirror))
    )
    (fp_text user "License: Apache-2.0" (at -0.939 -5.799 180) (layer "B.Fab") hide
        (effects (font (size 0.7 0.7) (thickness 0.15)) (justify left bottom mirror))
    )
    (fp_text user "${REFERENCE}" (at -0.939 -4.599 180) (layer "B.Fab") hide
        (effects (font (size 0.7 0.7) (thickness 0.15)) (justify left bottom mirror))
    )
    (fp_rect (start -0.925 0.47) (end 0.925 -0.47)
      (stroke (width 0.05) (type default)) (fill none) (layer "B.CrtYd"))
    (fp_line (start -0.494 -0.248) (end -0.494 0.25)
      (stroke (width 0.15) (type solid)) (layer "B.Fab"))
    (fp_line (start -0.494 0.25) (end 0.504 0.25)
      (stroke (width 0.15) (type solid)) (layer "B.Fab"))
    (fp_line (start 0.504 -0.248) (end -0.494 -0.248)
      (stroke (width 0.15) (type solid)) (layer "B.Fab"))
    (fp_line (start 0.504 0.25) (end 0.504 -0.248)
      (stroke (width 0.15) (type solid)) (layer "B.Fab"))
    (pad "1" smd roundrect (at -0.48 0) (size 0.59 0.64) (layers "B.Cu" "B.Paste" "B.Mask") (roundrect_rratio 0.25)
      (net 1 "GND") (pintype "passive"))
    (pad "2" smd roundrect (at 0.48 0) (size 0.59 0.64) (layers "B.Cu" "B.Paste" "B.Mask") (roundrect_rratio 0.25)
      (net 112 "Net-(U4A-VCC0P9_SVR_SENSE)") (pintype "passive"))
  )
	(footprint "antmicro-footprints:NetTie-2_SMD_Pad0.127mm" (layer "B.Cu")
    (at 116.16 86.35 -135)
    (descr "Net tie, 2 pin, 0.127mm  SMD pads")
    (tags "net tie")
    (property "Author" "Antmicro")
    (property "License" "Apache-2.0")
    (property "MPN" "")
    (property "Manufacturer" "")
    (property "Sheetfile" "power.kicad_sch")
    (property "Sheetname" "Power")
    (property "exclude_from_bom" "")
    (property "ki_description" "Net tie, 2 pins")
    (attr through_hole exclude_from_pos_files exclude_from_bom)
    (net_tie_pad_groups "1, 2")
    (fp_text reference "TP10" (at -0.128 1.345 45) (layer "B.SilkS") hide
        (effects (font (size 0.7 0.7) (thickness 0.15)) (justify left bottom mirror))
    )
    (fp_text value "Net-Tie_P0.127mm" (at 0 -1.199 45) (layer "B.Fab")
        (effects (font (size 0.7 0.7) (thickness 0.15)) (justify left bottom mirror))
    )
    (fp_text user "License: Apache-2.0" (at -0.128 -5.6 45) (layer "B.Fab") hide
        (effects (font (size 0.7 0.7) (thickness 0.15)) (justify left bottom mirror))
    )
    (fp_text user "${REFERENCE}" (at -0.128 -3.2 45) (layer "B.Fab") hide
        (effects (font (size 0.7 0.7) (thickness 0.15)) (justify left bottom mirror))
    )
    (fp_text user "Author: Antmicro" (at -0.128 -4.4 45) (layer "B.Fab") hide
        (effects (font (size 0.7 0.7) (thickness 0.15)) (justify left bottom mirror))
    )
    (fp_poly
      (pts
        (xy -0.0635 0.0635)
        (xy 0.0625 0.0635)
        (xy 0.0625 -0.0635)
        (xy -0.0635 -0.0635)
      )

      (stroke (width 0) (type solid)) (fill solid) (layer "B.Cu"))
    (fp_poly
      (pts
        (xy 0.2 0.16)
        (xy 0.29 0.07)
        (xy 0.29 -0.07)
        (xy 0.2 -0.16)
        (xy -0.2 -0.16)
        (xy -0.29 -0.07)
        (xy -0.29 0.06)
        (xy -0.19 0.16)
      )

      (stroke (width 0.05) (type solid)) (fill none) (layer "B.CrtYd"))
    (pad "1" smd roundrect (at -0.127 0 45) (size 0.127 0.127) (layers "B.Cu") (roundrect_rratio 0.5)
      (chamfer_ratio 0) (chamfer top_left bottom_left)
      (net 75 "Net-(C32-Pad2)") (pinfunction "1") (pintype "passive"))
    (pad "2" smd roundrect (at 0.126 0 225) (size 0.127 0.127) (layers "B.Cu") (roundrect_rratio 0.5)
      (chamfer_ratio 0) (chamfer top_left bottom_left)
      (net 84 "/Power/I_SENSE_P") (pinfunction "2") (pintype "passive"))
  )
	(footprint "antmicro-footprints:R_0402_1005Metric" (layer "B.Cu")
    (at 137.225 66.82 -90)
    (descr "Resistor SMD 0402")
    (tags "resistor SMD 0402")
    (property "Author" "Antmicro")
    (property "License" "Apache-2.0")
    (property "MPN" "CR0402-FX-2201GLF")
    (property "Manufacturer" "Bourns")
    (property "Sheetfile" "tb.kicad_sch")
    (property "Sheetname" "TB Controller")
    (property "Tolerance" "1%")
    (property "Val" "2k2")
    (property "ki_description" "SMD Chip Resistor, 2.2 kohm, ± 1%, 62.5 mW, 0402 [1005 Metric], Thick Film, General Purpose")
    (property "ki_keywords" "0402, SMT, RESISTOR, PASSIVE")
    (attr smd)
    (fp_text reference "R59" (at -3.066 -0.325 90) (layer "B.SilkS")
        (effects (font (size 0.7 0.7) (thickness 0.15)) (justify left bottom mirror))
    )
    (fp_text value "R_2k2_0402" (at -1.011843 -1.772047 90) (layer "B.Fab")
        (effects (font (size 0.7 0.7) (thickness 0.15)) (justify left bottom mirror))
    )
    (fp_text user "License: Apache-2.0" (at -0.95 -5.169 90) (layer "B.Fab") hide
        (effects (font (size 0.7 0.7) (thickness 0.15)) (justify left bottom mirror))
    )
    (fp_text user "Author: Antmicro" (at -0.95 -4.169 90) (layer "B.Fab") hide
        (effects (font (size 0.7 0.7) (thickness 0.15)) (justify left bottom mirror))
    )
    (fp_text user "${REFERENCE}" (at -0.95 -3.168 90) (layer "B.Fab") hide
        (effects (font (size 0.7 0.7) (thickness 0.15)) (justify left bottom mirror))
    )
    (fp_rect (start -0.925 0.47) (end 0.925 -0.47)
      (stroke (width 0.05) (type default)) (fill none) (layer "B.CrtYd"))
    (fp_rect (start -0.5 0.25) (end 0.5 -0.25)
      (stroke (width 0.15) (type solid)) (fill none) (layer "B.Fab"))
    (pad "1" smd roundrect (at -0.48 0 270) (size 0.59 0.64) (layers "B.Cu" "B.Paste" "B.Mask") (roundrect_rratio 0.25)
      (net 1 "GND") (pintype "passive"))
    (pad "2" smd roundrect (at 0.48 0 270) (size 0.59 0.64) (layers "B.Cu" "B.Paste" "B.Mask") (roundrect_rratio 0.25)
      (net 173 "Net-(U4C-DPSNK0_DDC_DATA)") (pintype "passive"))
  )
	(footprint "antmicro-footprints:C_0402_1005Metric" (layer "B.Cu")
    (at 157.41 63.97 180)
    (descr "Capacitor SMD 0402")
    (tags "capacitor SMD 0402")
    (property "Author" "Antmicro")
    (property "Dielectric" "")
    (property "License" "Apache-2.0")
    (property "MPN" "CC0402KRX5R6BB224")
    (property "Manufacturer" "YAGEO")
    (property "Sheetfile" "power.kicad_sch")
    (property "Sheetname" "Power")
    (property "Val" "220n")
    (property "Voltage" "")
    (property "ki_description" "SMD Multilayer Ceramic Capacitor, 0.22 µF, 10 V, 0402 [1005 Metric], ± 10%, X5R, CC Series")
    (property "ki_keywords" "0402, SMT, CAPACITOR, PASSIVE, MLCC, CERAMIC")
    (attr smd)
    (fp_text reference "C31" (at -0.987545 -1.435686) (layer "B.SilkS")
        (effects (font (size 0.7 0.7) (thickness 0.15)) (justify left bottom mirror))
    )
    (fp_text value "C_220n_0402" (at -1.022927 -2.155213) (layer "B.Fab")
        (effects (font (size 0.7 0.7) (thickness 0.15)) (justify left bottom mirror))
    )
    (fp_text user "Author: Antmicro" (at -0.939 -3.399) (layer "B.Fab") hide
        (effects (font (size 0.7 0.7) (thickness 0.15)) (justify left bottom mirror))
    )
    (fp_text user "${REFERENCE}" (at -0.939 -4.599) (layer "B.Fab") hide
        (effects (font (size 0.7 0.7) (thickness 0.15)) (justify left bottom mirror))
    )
    (fp_text user "License: Apache-2.0" (at -0.939 -5.799) (layer "B.Fab") hide
        (effects (font (size 0.7 0.7) (thickness 0.15)) (justify left bottom mirror))
    )
    (fp_rect (start -0.925 0.47) (end 0.925 -0.47)
      (stroke (width 0.05) (type default)) (fill none) (layer "B.CrtYd"))
    (fp_line (start -0.494 -0.248) (end -0.494 0.25)
      (stroke (width 0.15) (type solid)) (layer "B.Fab"))
    (fp_line (start -0.494 0.25) (end 0.504 0.25)
      (stroke (width 0.15) (type solid)) (layer "B.Fab"))
    (fp_line (start 0.504 -0.248) (end -0.494 -0.248)
      (stroke (width 0.15) (type solid)) (layer "B.Fab"))
    (fp_line (start 0.504 0.25) (end 0.504 -0.248)
      (stroke (width 0.15) (type solid)) (layer "B.Fab"))
    (pad "1" smd roundrect (at -0.48 0 180) (size 0.59 0.64) (layers "B.Cu" "B.Paste" "B.Mask") (roundrect_rratio 0.25)
      (net 1 "GND") (pintype "passive"))
    (pad "2" smd roundrect (at 0.48 0 180) (size 0.59 0.64) (layers "B.Cu" "B.Paste" "B.Mask") (roundrect_rratio 0.25)
      (net 98 "Net-(U3-SS)") (pintype "passive"))
  )
	(footprint "antmicro-footprints:C_0402_1005Metric" (layer "B.Cu")
    (at 139.175 81.3 90)
    (descr "Capacitor SMD 0402")
    (tags "capacitor SMD 0402")
    (property "Author" "Antmicro")
    (property "Dielectric" "")
    (property "License" "Apache-2.0")
    (property "MPN" "C1005X6S1A105K050BC")
    (property "Manufacturer" "TDK")
    (property "Sheetfile" "tb-power.kicad_sch")
    (property "Sheetname" "Thunderbolt Controller - Power")
    (property "Val" "1u")
    (property "Voltage" "")
    (property "ki_description" "SMD Multilayer Ceramic Capacitor, 1 µF, 10 V, 0402 [1005 Metric], ± 10%, X6S, C")
    (property "ki_keywords" "0402, SMT, CAPACITOR, PASSIVE, CERAMIC, MLCC")
    (attr smd)
    (fp_text reference "C81" (at -6.584 16.781 270) (layer "B.SilkS")
        (effects (font (size 0.7 0.7) (thickness 0.15)) (justify left bottom mirror))
    )
    (fp_text value "C_1u_0402" (at -1.022927 -2.155213 270) (layer "B.Fab")
        (effects (font (size 0.7 0.7) (thickness 0.15)) (justify left bottom mirror))
    )
    (fp_text user "Author: Antmicro" (at -0.939 -3.399 270) (layer "B.Fab") hide
        (effects (font (size 0.7 0.7) (thickness 0.15)) (justify left bottom mirror))
    )
    (fp_text user "${REFERENCE}" (at -0.939 -4.599 270) (layer "B.Fab") hide
        (effects (font (size 0.7 0.7) (thickness 0.15)) (justify left bottom mirror))
    )
    (fp_text user "License: Apache-2.0" (at -0.939 -5.799 270) (layer "B.Fab") hide
        (effects (font (size 0.7 0.7) (thickness 0.15)) (justify left bottom mirror))
    )
    (fp_rect (start -0.925 0.47) (end 0.925 -0.47)
      (stroke (width 0.05) (type default)) (fill none) (layer "B.CrtYd"))
    (fp_line (start -0.494 -0.248) (end -0.494 0.25)
      (stroke (width 0.15) (type solid)) (layer "B.Fab"))
    (fp_line (start -0.494 0.25) (end 0.504 0.25)
      (stroke (width 0.15) (type solid)) (layer "B.Fab"))
    (fp_line (start 0.504 -0.248) (end -0.494 -0.248)
      (stroke (width 0.15) (type solid)) (layer "B.Fab"))
    (fp_line (start 0.504 0.25) (end 0.504 -0.248)
      (stroke (width 0.15) (type solid)) (layer "B.Fab"))
    (pad "1" smd roundrect (at -0.48 0 90) (size 0.59 0.64) (layers "B.Cu" "B.Paste" "B.Mask") (roundrect_rratio 0.25)
      (net 1 "GND") (pintype "passive"))
    (pad "2" smd roundrect (at 0.48 0 90) (size 0.59 0.64) (layers "B.Cu" "B.Paste" "B.Mask") (roundrect_rratio 0.25)
      (net 112 "Net-(U4A-VCC0P9_SVR_SENSE)") (pintype "passive"))
  )
	(footprint "antmicro-footprints:R_0402_1005Metric" (layer "B.Cu")
    (at 155.91 59.47 90)
    (descr "Resistor SMD 0402")
    (tags "resistor SMD 0402")
    (property "Author" "Antmicro")
    (property "License" "Apache-2.0")
    (property "MPN" "CR0402-FX-1003GLF")
    (property "Manufacturer" "Bourns")
    (property "Sheetfile" "power.kicad_sch")
    (property "Sheetname" "Power")
    (property "Tolerance" "1%")
    (property "Val" "100k")
    (property "ki_description" "SMD Chip Resistor, 100 kohm, ± 1%, 62.5 mW, 0402 [1005 Metric], Thick Film, General Purpose")
    (property "ki_keywords" "0402, SMT, RESISTOR, PASSIVE")
    (attr smd)
    (fp_text reference "R29" (at 4.86 -5.542 270) (layer "B.SilkS")
        (effects (font (size 0.7 0.7) (thickness 0.15)) (justify left bottom mirror))
    )
    (fp_text value "R_100k_0402" (at -1.011843 -1.772047 270) (layer "B.Fab")
        (effects (font (size 0.7 0.7) (thickness 0.15)) (justify left bottom mirror))
    )
    (fp_text user "License: Apache-2.0" (at -0.95 -5.169 270) (layer "B.Fab") hide
        (effects (font (size 0.7 0.7) (thickness 0.15)) (justify left bottom mirror))
    )
    (fp_text user "Author: Antmicro" (at -0.95 -4.169 270) (layer "B.Fab") hide
        (effects (font (size 0.7 0.7) (thickness 0.15)) (justify left bottom mirror))
    )
    (fp_text user "${REFERENCE}" (at -0.95 -3.168 270) (layer "B.Fab") hide
        (effects (font (size 0.7 0.7) (thickness 0.15)) (justify left bottom mirror))
    )
    (fp_rect (start -0.925 0.47) (end 0.925 -0.47)
      (stroke (width 0.05) (type default)) (fill none) (layer "B.CrtYd"))
    (fp_rect (start -0.5 0.25) (end 0.5 -0.25)
      (stroke (width 0.15) (type solid)) (fill none) (layer "B.Fab"))
    (pad "1" smd roundrect (at -0.48 0 90) (size 0.59 0.64) (layers "B.Cu" "B.Paste" "B.Mask") (roundrect_rratio 0.25)
      (net 162 "Net-(U3-DEBUG_CTL2(GPIO17,_I2CADDR_B5))") (pintype "passive"))
    (pad "2" smd roundrect (at 0.48 0 90) (size 0.59 0.64) (layers "B.Cu" "B.Paste" "B.Mask") (roundrect_rratio 0.25)
      (net 9 "/Power/TPS_3V3") (pintype "passive"))
  )
	(footprint "antmicro-footprints:R_0402_1005Metric" (layer "B.Cu")
    (at 145.62 74.959999)
    (descr "Resistor SMD 0402")
    (tags "resistor SMD 0402")
    (property "Author" "Antmicro")
    (property "License" "Apache-2.0")
    (property "MPN" "CR0402-FX-1004GLF")
    (property "Manufacturer" "Bourns")
    (property "Sheetfile" "tb.kicad_sch")
    (property "Sheetname" "TB Controller")
    (property "Tolerance" "1%")
    (property "Val" "1M")
    (property "ki_description" "SMD Chip Resistor, 1 Mohm, ± 1%, 62.5 mW, 0402 [1005 Metric], Thick Film, General Purpose")
    (property "ki_keywords" "0402, SMT, RESISTOR, PASSIVE")
    (attr smd)
    (fp_text reference "R54" (at 3.097 0.351001 180) (layer "B.SilkS")
        (effects (font (size 0.7 0.7) (thickness 0.15)) (justify left bottom mirror))
    )
    (fp_text value "R_1M_0402" (at -1.011843 -1.772047 180) (layer "B.Fab")
        (effects (font (size 0.7 0.7) (thickness 0.15)) (justify left bottom mirror))
    )
    (fp_text user "${REFERENCE}" (at -0.95 -3.168 180) (layer "B.Fab") hide
        (effects (font (size 0.7 0.7) (thickness 0.15)) (justify left bottom mirror))
    )
    (fp_text user "License: Apache-2.0" (at -0.95 -5.169 180) (layer "B.Fab") hide
        (effects (font (size 0.7 0.7) (thickness 0.15)) (justify left bottom mirror))
    )
    (fp_text user "Author: Antmicro" (at -0.95 -4.169 180) (layer "B.Fab") hide
        (effects (font (size 0.7 0.7) (thickness 0.15)) (justify left bottom mirror))
    )
    (fp_rect (start -0.925 0.47) (end 0.925 -0.47)
      (stroke (width 0.05) (type default)) (fill none) (layer "B.CrtYd"))
    (fp_rect (start -0.5 0.25) (end 0.5 -0.25)
      (stroke (width 0.15) (type solid)) (fill none) (layer "B.Fab"))
    (pad "1" smd roundrect (at -0.48 0) (size 0.59 0.64) (layers "B.Cu" "B.Paste" "B.Mask") (roundrect_rratio 0.25)
      (net 1 "GND") (pintype "passive"))
    (pad "2" smd roundrect (at 0.48 0) (size 0.59 0.64) (layers "B.Cu" "B.Paste" "B.Mask") (roundrect_rratio 0.25)
      (net 66 "LSX_P2R") (pintype "passive"))
  )
	(footprint "antmicro-footprints:C_0402_1005Metric" (layer "B.Cu")
    (at 138.2 81.3 90)
    (descr "Capacitor SMD 0402")
    (tags "capacitor SMD 0402")
    (property "Author" "Antmicro")
    (property "Dielectric" "")
    (property "License" "Apache-2.0")
    (property "MPN" "C1005X6S1A105K050BC")
    (property "Manufacturer" "TDK")
    (property "Sheetfile" "tb-power.kicad_sch")
    (property "Sheetname" "Thunderbolt Controller - Power")
    (property "Val" "1u")
    (property "Voltage" "")
    (property "ki_description" "SMD Multilayer Ceramic Capacitor, 1 µF, 10 V, 0402 [1005 Metric], ± 10%, X6S, C")
    (property "ki_keywords" "0402, SMT, CAPACITOR, PASSIVE, CERAMIC, MLCC")
    (attr smd)
    (fp_text reference "C84" (at -6.584 16.867 270) (layer "B.SilkS")
        (effects (font (size 0.7 0.7) (thickness 0.15)) (justify left bottom mirror))
    )
    (fp_text value "C_1u_0402" (at -1.022927 -2.155213 270) (layer "B.Fab")
        (effects (font (size 0.7 0.7) (thickness 0.15)) (justify left bottom mirror))
    )
    (fp_text user "License: Apache-2.0" (at -0.939 -5.799 270) (layer "B.Fab") hide
        (effects (font (size 0.7 0.7) (thickness 0.15)) (justify left bottom mirror))
    )
    (fp_text user "Author: Antmicro" (at -0.939 -3.399 270) (layer "B.Fab") hide
        (effects (font (size 0.7 0.7) (thickness 0.15)) (justify left bottom mirror))
    )
    (fp_text user "${REFERENCE}" (at -0.939 -4.599 270) (layer "B.Fab") hide
        (effects (font (size 0.7 0.7) (thickness 0.15)) (justify left bottom mirror))
    )
    (fp_rect (start -0.925 0.47) (end 0.925 -0.47)
      (stroke (width 0.05) (type default)) (fill none) (layer "B.CrtYd"))
    (fp_line (start -0.494 -0.248) (end -0.494 0.25)
      (stroke (width 0.15) (type solid)) (layer "B.Fab"))
    (fp_line (start -0.494 0.25) (end 0.504 0.25)
      (stroke (width 0.15) (type solid)) (layer "B.Fab"))
    (fp_line (start 0.504 -0.248) (end -0.494 -0.248)
      (stroke (width 0.15) (type solid)) (layer "B.Fab"))
    (fp_line (start 0.504 0.25) (end 0.504 -0.248)
      (stroke (width 0.15) (type solid)) (layer "B.Fab"))
    (pad "1" smd roundrect (at -0.48 0 90) (size 0.59 0.64) (layers "B.Cu" "B.Paste" "B.Mask") (roundrect_rratio 0.25)
      (net 1 "GND") (pintype "passive"))
    (pad "2" smd roundrect (at 0.48 0 90) (size 0.59 0.64) (layers "B.Cu" "B.Paste" "B.Mask") (roundrect_rratio 0.25)
      (net 112 "Net-(U4A-VCC0P9_SVR_SENSE)") (pintype "passive"))
  )
)
